(kicad_pcb
	(version 20260206)
	(generator "pcbnew")
	(generator_version "10.0")
	(general
		(thickness 1.6)
		(legacy_teardrops no)
	)
	(paper "A4")
	(title_block
		(title "baseboard — 13948-1b.1110WZS1818.brd")
		(comment 1 "Honey Badger (Wiwynn) / footprints 509-512 of 2523")
	)
	(layers
		(0 "F.Cu" signal "TOP")
		(4 "In1.Cu" signal "L2GND")
		(6 "In2.Cu" signal "L3")
		(8 "In3.Cu" signal "L4VCC")
		(10 "In4.Cu" signal "L5VCC")
		(12 "In5.Cu" signal "L6")
		(14 "In6.Cu" signal "L7GND")
		(2 "B.Cu" signal "BOTTOM")
		(9 "F.Adhes" user "F.Adhesive")
		(11 "B.Adhes" user "B.Adhesive")
		(13 "F.Paste" user "Package Geometry/Pastemask Top")
		(15 "B.Paste" user "Package Geometry/Pastemask Bottom")
		(5 "F.SilkS" user "Ref Des/Silkscreen Top")
		(7 "B.SilkS" user "Ref Des/Silkscreen Bottom")
		(1 "F.Mask" user "Board Geometry/Soldermask Top")
		(3 "B.Mask" user "Board Geometry/Soldermask Bottom")
		(17 "Dwgs.User" user "User.Drawings")
		(19 "Cmts.User" user "User.Comments")
		(21 "Eco1.User" user "User.Eco1")
		(23 "Eco2.User" user "User.Eco2")
		(25 "Edge.Cuts" user "Board Geometry/Outline")
		(27 "Margin" user)
		(31 "F.CrtYd" user "Package Geometry/Place Bound Top")
		(29 "B.CrtYd" user "Package Geometry/Place Bound Bottom")
		(35 "F.Fab" user "Ref Des/Assembly Top")
		(33 "B.Fab" user "Ref Des/Assembly Bottom")
	)
	(footprint ""
		(layer "F.Cu")
		(at 223.266 -83.82 90)
		(property "Reference" "C311"
			(at 0 0 90)
			(layer "F.SilkS")
			(hide yes)
			(effects
				(font
					(size 1.27 1.27)
				)
			)
		)
		(property "Value" "SC1U25V3KX-GP"
			(at 0 -2.8194 90)
			(unlocked yes)
			(layer "F.Fab")
			(hide yes)
			(effects
				(font
					(size 1.016 1.016)
					(thickness 0.1524)
				)
			)
		)
		(property "Device Type" "C603H36"
			(at 0 -4.3434 90)
			(unlocked yes)
			(layer "F.Fab")
			(hide yes)
			(effects
				(font
					(size 1.016 1.016)
					(thickness 0.1524)
				)
			)
		)
		(duplicate_pad_numbers_are_jumpers no)
		(fp_line
			(start 0.508 0)
			(end -0.508 0)
			(stroke
				(width 0.2032)
				(type default)
			)
			(layer "F.SilkS")
		)
		(fp_rect
			(start -0.5842 1.3335)
			(end 0.5842 -1.3335)
			(stroke
				(width 0)
				(type default)
			)
			(fill no)
			(layer "F.CrtYd")
		)
		(fp_rect
			(start -0.5842 1.3335)
			(end 0.5842 -1.3335)
			(stroke
				(width 0)
				(type default)
			)
			(fill no)
			(layer "F.Fab")
		)
		(pad "1" smd custom
			(at 0 -0.762 90)
			(size 0.2159 0.2159)
			(layers "F.Cu" "F.Mask" "F.Paste")
			(net "P12V_MSB")
			(options
				(clearance outline)
				(anchor circle)
			)
			(primitives
				(gr_poly
					(pts
						(arc
							(start -0.3302 -0.4318)
							(mid -0.402042 -0.402042)
							(end -0.4318 -0.3302)
						)
						(arc
							(start -0.4318 0.3302)
							(mid -0.402042 0.402042)
							(end -0.3302 0.4318)
						)
						(arc
							(start 0.3302 0.4318)
							(mid 0.402042 0.402042)
							(end 0.4318 0.3302)
						)
						(arc
							(start 0.4318 -0.3302)
							(mid 0.402042 -0.402042)
							(end 0.3302 -0.4318)
						)
					)
					(width 0)
					(fill yes)
				)
			)
		)
		(pad "2" smd custom
			(at 0 0.762 90)
			(size 0.2159 0.2159)
			(layers "F.Cu" "F.Mask" "F.Paste")
			(net "GND")
			(options
				(clearance outline)
				(anchor circle)
			)
			(primitives
				(gr_poly
					(pts
						(arc
							(start -0.3302 -0.4318)
							(mid -0.402042 -0.402042)
							(end -0.4318 -0.3302)
						)
						(arc
							(start -0.4318 0.3302)
							(mid -0.402042 0.402042)
							(end -0.3302 0.4318)
						)
						(arc
							(start 0.3302 0.4318)
							(mid 0.402042 0.402042)
							(end 0.4318 0.3302)
						)
						(arc
							(start 0.4318 -0.3302)
							(mid 0.402042 -0.402042)
							(end 0.3302 -0.4318)
						)
					)
					(width 0)
					(fill yes)
				)
			)
		)
	)
	(footprint ""
		(layer "F.Cu")
		(at 57.179972 -186.539886)
		(property "Reference" "SCN3"
			(at 0 0 0)
			(layer "F.SilkS")
			(hide yes)
			(effects
				(font
					(size 1.27 1.27)
				)
			)
		)
		(property "Value" "MLX-CONN20A-S3-GP"
			(at -17.870678 -4.036822 0)
			(unlocked yes)
			(layer "F.Fab")
			(hide yes)
			(effects
				(font
					(size 1.016 1.016)
					(thickness 0.1524)
				)
			)
		)
		(property "Device Type" "70246-2001"
			(at -17.870678 -5.560822 0)
			(unlocked yes)
			(layer "F.Fab")
			(hide yes)
			(effects
				(font
					(size 1.016 1.016)
					(thickness 0.1524)
				)
			)
		)
		(duplicate_pad_numbers_are_jumpers no)
		(fp_line
			(start -16.891 3.556)
			(end -16.891 4.826)
			(stroke
				(width 0.4064)
				(type default)
			)
			(layer "F.SilkS")
		)
		(fp_line
			(start -16.891 4.826)
			(end -15.621 4.826)
			(stroke
				(width 0.4064)
				(type default)
			)
			(layer "F.SilkS")
		)
		(fp_line
			(start -16.764 -4.699)
			(end 16.764 -4.699)
			(stroke
				(width 0.1524)
				(type default)
			)
			(layer "F.SilkS")
		)
		(fp_line
			(start -16.764 4.699)
			(end -16.764 -4.699)
			(stroke
				(width 0.1524)
				(type default)
			)
			(layer "F.SilkS")
		)
		(fp_line
			(start -2.0574 4.191)
			(end 2.0574 4.191)
			(stroke
				(width 0.1524)
				(type default)
			)
			(layer "F.SilkS")
		)
		(fp_line
			(start -2.0574 4.699)
			(end -2.0574 4.191)
			(stroke
				(width 0.1524)
				(type default)
			)
			(layer "F.SilkS")
		)
		(fp_line
			(start 2.0574 4.191)
			(end 2.0574 4.699)
			(stroke
				(width 0.1524)
				(type default)
			)
			(layer "F.SilkS")
		)
		(fp_line
			(start 16.764 -4.699)
			(end 16.764 4.699)
			(stroke
				(width 0.1524)
				(type default)
			)
			(layer "F.SilkS")
		)
		(fp_line
			(start 16.764 4.699)
			(end -16.764 4.699)
			(stroke
				(width 0.1524)
				(type default)
			)
			(layer "F.SilkS")
		)
		(fp_circle
			(center -11.43 -1.27)
			(end -10.2997 -1.27)
			(stroke
				(width 0.3048)
				(type default)
			)
			(fill no)
			(layer "F.SilkS")
		)
		(fp_circle
			(center -11.43 1.27)
			(end -10.2997 1.27)
			(stroke
				(width 0.3048)
				(type default)
			)
			(fill no)
			(layer "F.SilkS")
		)
		(fp_circle
			(center -8.89 -1.27)
			(end -7.7597 -1.27)
			(stroke
				(width 0.3048)
				(type default)
			)
			(fill no)
			(layer "F.SilkS")
		)
		(fp_circle
			(center -8.89 1.27)
			(end -7.7597 1.27)
			(stroke
				(width 0.3048)
				(type default)
			)
			(fill no)
			(layer "F.SilkS")
		)
		(fp_circle
			(center -6.35 -1.27)
			(end -5.2197 -1.27)
			(stroke
				(width 0.3048)
				(type default)
			)
			(fill no)
			(layer "F.SilkS")
		)
		(fp_circle
			(center -6.35 1.27)
			(end -5.2197 1.27)
			(stroke
				(width 0.3048)
				(type default)
			)
			(fill no)
			(layer "F.SilkS")
		)
		(fp_circle
			(center -3.81 -1.27)
			(end -2.6797 -1.27)
			(stroke
				(width 0.3048)
				(type default)
			)
			(fill no)
			(layer "F.SilkS")
		)
		(fp_circle
			(center -3.81 1.27)
			(end -2.6797 1.27)
			(stroke
				(width 0.3048)
				(type default)
			)
			(fill no)
			(layer "F.SilkS")
		)
		(fp_circle
			(center -1.27 -1.27)
			(end -0.1397 -1.27)
			(stroke
				(width 0.3048)
				(type default)
			)
			(fill no)
			(layer "F.SilkS")
		)
		(fp_circle
			(center -1.27 1.27)
			(end -0.1397 1.27)
			(stroke
				(width 0.3048)
				(type default)
			)
			(fill no)
			(layer "F.SilkS")
		)
		(fp_circle
			(center 1.27 -1.27)
			(end 2.4003 -1.27)
			(stroke
				(width 0.3048)
				(type default)
			)
			(fill no)
			(layer "F.SilkS")
		)
		(fp_circle
			(center 1.27 1.27)
			(end 2.4003 1.27)
			(stroke
				(width 0.3048)
				(type default)
			)
			(fill no)
			(layer "F.SilkS")
		)
		(fp_circle
			(center 3.81 -1.27)
			(end 4.9403 -1.27)
			(stroke
				(width 0.3048)
				(type default)
			)
			(fill no)
			(layer "F.SilkS")
		)
		(fp_circle
			(center 3.81 1.27)
			(end 4.9403 1.27)
			(stroke
				(width 0.3048)
				(type default)
			)
			(fill no)
			(layer "F.SilkS")
		)
		(fp_circle
			(center 6.35 -1.27)
			(end 7.4803 -1.27)
			(stroke
				(width 0.3048)
				(type default)
			)
			(fill no)
			(layer "F.SilkS")
		)
		(fp_circle
			(center 6.35 1.27)
			(end 7.4803 1.27)
			(stroke
				(width 0.3048)
				(type default)
			)
			(fill no)
			(layer "F.SilkS")
		)
		(fp_circle
			(center 8.89 -1.27)
			(end 10.0203 -1.27)
			(stroke
				(width 0.3048)
				(type default)
			)
			(fill no)
			(layer "F.SilkS")
		)
		(fp_circle
			(center 8.89 1.27)
			(end 10.0203 1.27)
			(stroke
				(width 0.3048)
				(type default)
			)
			(fill no)
			(layer "F.SilkS")
		)
		(fp_circle
			(center 11.43 -1.27)
			(end 12.5603 -1.27)
			(stroke
				(width 0.3048)
				(type default)
			)
			(fill no)
			(layer "F.SilkS")
		)
		(fp_circle
			(center 11.43 1.27)
			(end 12.5603 1.27)
			(stroke
				(width 0.3048)
				(type default)
			)
			(fill no)
			(layer "F.SilkS")
		)
		(fp_rect
			(start -16.51 4.445)
			(end 16.51 -4.445)
			(stroke
				(width 0)
				(type default)
			)
			(fill no)
			(layer "F.CrtYd")
		)
		(fp_poly
			(pts
				(xy -17.018 4.953) (xy -17.018 -4.953) (xy 17.018 -4.953) (xy 17.018 4.953) (xy 0.00508 4.953) (xy 0.00508 4.445)
				(xy 16.51 4.445) (xy 16.51 -4.445) (xy -16.51 -4.445) (xy -16.51 4.445) (xy 0 4.445) (xy 0 4.953)
			)
			(stroke
				(width 0)
				(type default)
			)
			(fill no)
			(layer "F.CrtYd")
		)
		(fp_rect
			(start -17.018 4.953)
			(end 17.018 -4.953)
			(stroke
				(width 0)
				(type default)
			)
			(fill no)
			(layer "F.Fab")
		)
		(pad "1" thru_hole circle
			(at -11.43 1.27)
			(size 1.5494 1.5494)
			(drill 1.143)
			(layers "*.Cu" "*.Mask")
			(remove_unused_layers no)
			(net "3D3V_ICE")
			(clearance 0.1524)
			(thermal_gap 0.1524)
		)
		(pad "2" thru_hole circle
			(at -11.43 -1.27)
			(size 1.5494 1.5494)
			(drill 1.143)
			(layers "*.Cu" "*.Mask")
			(remove_unused_layers no)
			(net "3D3V_ICE")
			(clearance 0.1524)
			(thermal_gap 0.1524)
		)
		(pad "3" thru_hole circle
			(at -8.89 1.27)
			(size 1.5494 1.5494)
			(drill 1.143)
			(layers "*.Cu" "*.Mask")
			(remove_unused_layers no)
			(net "ICE_TRST_N")
			(clearance 0.1524)
			(thermal_gap 0.1524)
		)
		(pad "4" thru_hole circle
			(at -8.89 -1.27)
			(size 1.5494 1.5494)
			(drill 1.143)
			(layers "*.Cu" "*.Mask")
			(remove_unused_layers no)
			(net "GND")
			(clearance 0.1524)
			(thermal_gap 0.1524)
		)
		(pad "5" thru_hole circle
			(at -6.35 1.27)
			(size 1.5494 1.5494)
			(drill 1.143)
			(layers "*.Cu" "*.Mask")
			(remove_unused_layers no)
			(net "ICE_TDI")
			(clearance 0.1524)
			(thermal_gap 0.1524)
		)
		(pad "6" thru_hole circle
			(at -6.35 -1.27)
			(size 1.5494 1.5494)
			(drill 1.143)
			(layers "*.Cu" "*.Mask")
			(remove_unused_layers no)
			(net "GND")
			(clearance 0.1524)
			(thermal_gap 0.1524)
		)
		(pad "7" thru_hole circle
			(at -3.81 1.27)
			(size 1.5494 1.5494)
			(drill 1.143)
			(layers "*.Cu" "*.Mask")
			(remove_unused_layers no)
			(net "ICE_TMS")
			(clearance 0.1524)
			(thermal_gap 0.1524)
		)
		(pad "8" thru_hole circle
			(at -3.81 -1.27)
			(size 1.5494 1.5494)
			(drill 1.143)
			(layers "*.Cu" "*.Mask")
			(remove_unused_layers no)
			(net "GND")
			(clearance 0.1524)
			(thermal_gap 0.1524)
		)
		(pad "9" thru_hole circle
			(at -1.27 1.27)
			(size 1.5494 1.5494)
			(drill 1.143)
			(layers "*.Cu" "*.Mask")
			(remove_unused_layers no)
			(net "ICE_TCK")
			(clearance 0.1524)
			(thermal_gap 0.1524)
		)
		(pad "10" thru_hole circle
			(at -1.27 -1.27)
			(size 1.5494 1.5494)
			(drill 1.143)
			(layers "*.Cu" "*.Mask")
			(remove_unused_layers no)
			(net "GND")
			(clearance 0.1524)
			(thermal_gap 0.1524)
		)
		(pad "11" thru_hole circle
			(at 1.27 1.27)
			(size 1.5494 1.5494)
			(drill 1.143)
			(layers "*.Cu" "*.Mask")
			(remove_unused_layers no)
			(net "GND")
			(clearance 0.1524)
			(thermal_gap 0.1524)
		)
		(pad "12" thru_hole circle
			(at 1.27 -1.27)
			(size 1.5494 1.5494)
			(drill 1.143)
			(layers "*.Cu" "*.Mask")
			(remove_unused_layers no)
			(net "GND")
			(clearance 0.1524)
			(thermal_gap 0.1524)
		)
		(pad "13" thru_hole circle
			(at 3.81 1.27)
			(size 1.5494 1.5494)
			(drill 1.143)
			(layers "*.Cu" "*.Mask")
			(remove_unused_layers no)
			(net "ICE_TDO")
			(clearance 0.1524)
			(thermal_gap 0.1524)
		)
		(pad "14" thru_hole circle
			(at 3.81 -1.27)
			(size 1.5494 1.5494)
			(drill 1.143)
			(layers "*.Cu" "*.Mask")
			(remove_unused_layers no)
			(net "GND")
			(clearance 0.1524)
			(thermal_gap 0.1524)
		)
		(pad "15" thru_hole circle
			(at 6.35 1.27)
			(size 1.5494 1.5494)
			(drill 1.143)
			(layers "*.Cu" "*.Mask")
			(remove_unused_layers no)
			(net "ICE_RESET_N")
			(clearance 0.1524)
			(thermal_gap 0.1524)
		)
		(pad "16" thru_hole circle
			(at 6.35 -1.27)
			(size 1.5494 1.5494)
			(drill 1.143)
			(layers "*.Cu" "*.Mask")
			(remove_unused_layers no)
			(net "GND")
			(clearance 0.1524)
			(thermal_gap 0.1524)
		)
		(pad "17" thru_hole circle
			(at 8.89 1.27)
			(size 1.5494 1.5494)
			(drill 1.143)
			(layers "*.Cu" "*.Mask")
			(remove_unused_layers no)
			(net "GND")
			(clearance 0.1524)
			(thermal_gap 0.1524)
		)
		(pad "18" thru_hole circle
			(at 8.89 -1.27)
			(size 1.5494 1.5494)
			(drill 1.143)
			(layers "*.Cu" "*.Mask")
			(remove_unused_layers no)
			(net "GND")
			(clearance 0.1524)
			(thermal_gap 0.1524)
		)
		(pad "19" thru_hole circle
			(at 11.43 1.27)
			(size 1.5494 1.5494)
			(drill 1.143)
			(layers "*.Cu" "*.Mask")
			(remove_unused_layers no)
			(net "GND")
			(clearance 0.1524)
			(thermal_gap 0.1524)
		)
		(pad "20" thru_hole circle
			(at 11.43 -1.27)
			(size 1.5494 1.5494)
			(drill 1.143)
			(layers "*.Cu" "*.Mask")
			(remove_unused_layers no)
			(net "GND")
			(clearance 0.1524)
			(thermal_gap 0.1524)
		)
	)
	(footprint ""
		(layer "F.Cu")
		(at 52.832 -224.917 180)
		(property "Reference" "R2109"
			(at 0 0 180)
			(layer "F.SilkS")
			(hide yes)
			(effects
				(font
					(size 1.27 1.27)
				)
			)
		)
		(property "Value" "6K04R2F-GP"
			(at 0.064008 -3.993896 180)
			(unlocked yes)
			(layer "F.Fab")
			(hide yes)
			(effects
				(font
					(size 1.016 1.016)
					(thickness 0.1524)
				)
			)
		)
		(property "Device Type" "R402H16"
			(at 0.064008 -5.517896 180)
			(unlocked yes)
			(layer "F.Fab")
			(hide yes)
			(effects
				(font
					(size 1.016 1.016)
					(thickness 0.1524)
				)
			)
		)
		(duplicate_pad_numbers_are_jumpers no)
		(fp_line
			(start 0.508 -0.9398)
			(end -0.508 -0.9398)
			(stroke
				(width 0.1524)
				(type default)
			)
			(layer "F.SilkS")
		)
		(fp_line
			(start -0.508 -0.9398)
			(end -0.508 0.9398)
			(stroke
				(width 0.1524)
				(type default)
			)
			(layer "F.SilkS")
		)
		(fp_rect
			(start -0.508 0.9398)
			(end 0.508 -0.9398)
			(stroke
				(width 0)
				(type default)
			)
			(fill no)
			(layer "F.CrtYd")
		)
		(fp_rect
			(start -0.508 0.9398)
			(end 0.508 -0.9398)
			(stroke
				(width 0)
				(type default)
			)
			(fill no)
			(layer "F.Fab")
		)
		(pad "1" smd custom
			(at 0 -0.4445 180)
			(size 0.1397 0.1397)
			(layers "F.Cu" "F.Mask" "F.Paste")
			(net "MB0_CM_UV_R")
			(options
				(clearance outline)
				(anchor circle)
			)
			(primitives
				(gr_poly
					(pts
						(arc
							(start -0.1778 -0.2794)
							(mid -0.249642 -0.249642)
							(end -0.2794 -0.1778)
						)
						(arc
							(start -0.2794 0.1778)
							(mid -0.249642 0.249642)
							(end -0.1778 0.2794)
						)
						(arc
							(start 0.1778 0.2794)
							(mid 0.249642 0.249642)
							(end 0.2794 0.1778)
						)
						(arc
							(start 0.2794 -0.1778)
							(mid 0.249642 -0.249642)
							(end 0.1778 -0.2794)
						)
					)
					(width 0)
					(fill yes)
				)
			)
		)
		(pad "2" smd custom
			(at 0 0.4445 180)
			(size 0.1397 0.1397)
			(layers "F.Cu" "F.Mask" "F.Paste")
			(net "AGND_CURRENT_MON")
			(options
				(clearance outline)
				(anchor circle)
			)
			(primitives
				(gr_poly
					(pts
						(arc
							(start -0.1778 -0.2794)
							(mid -0.249642 -0.249642)
							(end -0.2794 -0.1778)
						)
						(arc
							(start -0.2794 0.1778)
							(mid -0.249642 0.249642)
							(end -0.1778 0.2794)
						)
						(arc
							(start 0.1778 0.2794)
							(mid 0.249642 0.249642)
							(end 0.2794 0.1778)
						)
						(arc
							(start 0.2794 -0.1778)
							(mid 0.249642 -0.249642)
							(end 0.1778 -0.2794)
						)
					)
					(width 0)
					(fill yes)
				)
			)
		)
	)
	(footprint ""
		(layer "F.Cu")
		(at 287.782 -161.544 180)
		(property "Reference" "R252"
			(at 0 0 180)
			(layer "F.SilkS")
			(hide yes)
			(effects
				(font
					(size 1.27 1.27)
				)
			)
		)
		(property "Value" "0R2J-2-GP"
			(at 0.064008 -3.993896 180)
			(unlocked yes)
			(layer "F.Fab")
			(hide yes)
			(effects
				(font
					(size 1.016 1.016)
					(thickness 0.1524)
				)
			)
		)
		(property "Device Type" "R402H16"
			(at 0.064008 -5.517896 180)
			(unlocked yes)
			(layer "F.Fab")
			(hide yes)
			(effects
				(font
					(size 1.016 1.016)
					(thickness 0.1524)
				)
			)
		)
		(duplicate_pad_numbers_are_jumpers no)
		(fp_line
			(start 0.508 -0.9398)
			(end -0.508 -0.9398)
			(stroke
				(width 0.1524)
				(type default)
			)
			(layer "F.SilkS")
		)
		(fp_line
			(start -0.508 -0.9398)
			(end -0.508 0.9398)
			(stroke
				(width 0.1524)
				(type default)
			)
			(layer "F.SilkS")
		)
		(fp_rect
			(start -0.508 0.9398)
			(end 0.508 -0.9398)
			(stroke
				(width 0)
				(type default)
			)
			(fill no)
			(layer "F.CrtYd")
		)
		(fp_rect
			(start -0.508 0.9398)
			(end 0.508 -0.9398)
			(stroke
				(width 0)
				(type default)
			)
			(fill no)
			(layer "F.Fab")
		)
		(pad "1" smd custom
			(at 0 -0.4445 180)
			(size 0.1397 0.1397)
			(layers "F.Cu" "F.Mask" "F.Paste")
			(net "BMC_PWRBTN_N")
			(options
				(clearance outline)
				(anchor circle)
			)
			(primitives
				(gr_poly
					(pts
						(arc
							(start -0.1778 -0.2794)
							(mid -0.249642 -0.249642)
							(end -0.2794 -0.1778)
						)
						(arc
							(start -0.2794 0.1778)
							(mid -0.249642 0.249642)
							(end -0.1778 0.2794)
						)
						(arc
							(start 0.1778 0.2794)
							(mid 0.249642 0.249642)
							(end 0.2794 0.1778)
						)
						(arc
							(start 0.2794 -0.1778)
							(mid 0.249642 -0.249642)
							(end 0.1778 -0.2794)
						)
					)
					(width 0)
					(fill yes)
				)
			)
		)
		(pad "2" smd custom
			(at 0 0.4445 180)
			(size 0.1397 0.1397)
			(layers "F.Cu" "F.Mask" "F.Paste")
			(net "BMC_PWRBTN_N_R")
			(options
				(clearance outline)
				(anchor circle)
			)
			(primitives
				(gr_poly
					(pts
						(arc
							(start -0.1778 -0.2794)
							(mid -0.249642 -0.249642)
							(end -0.2794 -0.1778)
						)
						(arc
							(start -0.2794 0.1778)
							(mid -0.249642 0.249642)
							(end -0.1778 0.2794)
						)
						(arc
							(start 0.1778 0.2794)
							(mid 0.249642 0.249642)
							(end 0.2794 0.1778)
						)
						(arc
							(start 0.2794 -0.1778)
							(mid 0.249642 -0.249642)
							(end 0.1778 -0.2794)
						)
					)
					(width 0)
					(fill yes)
				)
			)
		)
	)
)
